(kicad_pcb
	(version 20260206)
	(generator "pcbnew")
	(generator_version "10.0")
	(general
		(thickness 1.6)
		(legacy_teardrops no)
	)
	(paper "A4")
	(title_block
		(title "03242023_DA0F0TMBIJ0_F0T_Motherboard_J_brd_V01_OCP.brd")
		(comment 1 "Grand Teton / footprints 610-615 of 6105")
	)
	(layers
		(0 "F.Cu" signal "TOP")
		(4 "In1.Cu" signal "GND")
		(6 "In2.Cu" signal "IN1")
		(8 "In3.Cu" signal "GND1")
		(10 "In4.Cu" signal "IN2")
		(12 "In5.Cu" signal "GND2")
		(14 "In6.Cu" signal "IN3")
		(16 "In7.Cu" signal "GND3")
		(18 "In8.Cu" signal "VCC")
		(20 "In9.Cu" signal "VCC1")
		(22 "In10.Cu" signal "GND4")
		(24 "In11.Cu" signal "IN4")
		(26 "In12.Cu" signal "GND5")
		(28 "In13.Cu" signal "IN5")
		(30 "In14.Cu" signal "GND6")
		(32 "In15.Cu" signal "IN6")
		(34 "In16.Cu" signal "GND7")
		(2 "B.Cu" signal "BOTTOM")
		(9 "F.Adhes" user "F.Adhesive")
		(11 "B.Adhes" user "B.Adhesive")
		(13 "F.Paste" user "Package Geometry/Pastemask Top")
		(15 "B.Paste" user "Package Geometry/Pastemask Bottom")
		(5 "F.SilkS" user "Ref Des/Silkscreen Top")
		(7 "B.SilkS" user "Ref Des/Silkscreen Bottom")
		(1 "F.Mask" user "Board Geometry/Soldermask Top")
		(3 "B.Mask" user "Board Geometry/Soldermask Bottom")
		(17 "Dwgs.User" user "User.Drawings")
		(19 "Cmts.User" user "User.Comments")
		(21 "Eco1.User" user "User.Eco1")
		(23 "Eco2.User" user "User.Eco2")
		(25 "Edge.Cuts" user "Board Geometry/Outline")
		(27 "Margin" user)
		(31 "F.CrtYd" user "Package Geometry/Place Bound Top")
		(29 "B.CrtYd" user "Package Geometry/Place Bound Bottom")
		(35 "F.Fab" user "Ref Des/Assembly Top")
		(33 "B.Fab" user "Ref Des/Assembly Bottom")
	)
	(footprint ""
		(layer "F.Cu")
		(at 106.990896 -338.180172 -90)
		(property "Reference" "PC564"
			(at 0 0 270)
			(layer "F.SilkS")
			(hide yes)
			(effects
				(font
					(size 1.27 1.27)
				)
			)
		)
		(property "Value" ""
			(at 0 0 270)
			(layer "F.Fab")
			(effects
				(font
					(size 1.27 1.27)
				)
			)
		)
		(duplicate_pad_numbers_are_jumpers no)
		(fp_line
			(start -0.7874 0.4064)
			(end -0.7874 -0.4064)
			(stroke
				(width 0.1524)
				(type default)
			)
			(layer "F.SilkS")
		)
		(fp_line
			(start 0.7874 0.4064)
			(end -0.7874 0.4064)
			(stroke
				(width 0.1524)
				(type default)
			)
			(layer "F.SilkS")
		)
		(fp_line
			(start -0.7874 -0.4064)
			(end 0.7874 -0.4064)
			(stroke
				(width 0.1524)
				(type default)
			)
			(layer "F.SilkS")
		)
		(fp_line
			(start 0.7874 -0.4064)
			(end 0.7874 0.4064)
			(stroke
				(width 0.1524)
				(type default)
			)
			(layer "F.SilkS")
		)
		(fp_line
			(start -0.67945 0.3048)
			(end -0.67945 -0.305054)
			(stroke
				(width 0.1)
				(type default)
			)
			(layer "F.Fab")
		)
		(fp_line
			(start -0.12065 0.3048)
			(end -0.67945 0.3048)
			(stroke
				(width 0.1)
				(type default)
			)
			(layer "F.Fab")
		)
		(fp_line
			(start 0.120396 0.3048)
			(end 0.120396 0.2794)
			(stroke
				(width 0.1)
				(type default)
			)
			(layer "F.Fab")
		)
		(fp_line
			(start 0.67945 0.3048)
			(end 0.120396 0.3048)
			(stroke
				(width 0.1)
				(type default)
			)
			(layer "F.Fab")
		)
		(fp_line
			(start -0.12065 0.2794)
			(end -0.12065 0.3048)
			(stroke
				(width 0.1)
				(type default)
			)
			(layer "F.Fab")
		)
		(fp_line
			(start 0.120396 0.2794)
			(end -0.12065 0.2794)
			(stroke
				(width 0.1)
				(type default)
			)
			(layer "F.Fab")
		)
		(fp_line
			(start -0.12065 -0.2794)
			(end 0.12065 -0.2794)
			(stroke
				(width 0.1)
				(type default)
			)
			(layer "F.Fab")
		)
		(fp_line
			(start 0.12065 -0.2794)
			(end 0.12065 -0.3048)
			(stroke
				(width 0.1)
				(type default)
			)
			(layer "F.Fab")
		)
		(fp_line
			(start 0.12065 -0.3048)
			(end 0.67945 -0.3048)
			(stroke
				(width 0.1)
				(type default)
			)
			(layer "F.Fab")
		)
		(fp_line
			(start 0.67945 -0.3048)
			(end 0.67945 0.3048)
			(stroke
				(width 0.1)
				(type default)
			)
			(layer "F.Fab")
		)
		(fp_line
			(start -0.67945 -0.305054)
			(end -0.12065 -0.305054)
			(stroke
				(width 0.1)
				(type default)
			)
			(layer "F.Fab")
		)
		(fp_line
			(start -0.12065 -0.305054)
			(end -0.12065 -0.2794)
			(stroke
				(width 0.1)
				(type default)
			)
			(layer "F.Fab")
		)
		(pad "1" smd circle
			(at -0.40005 0 270)
			(size 0 0)
			(layers "F.Cu" "F.Mask" "F.Paste")
			(net "SW_PVCCIN_CPU1_BOOT2_R")
		)
		(pad "2" smd circle
			(at 0.40005 0 270)
			(size 0 0)
			(layers "F.Cu" "F.Mask" "F.Paste")
			(net "SW_PVCCIN_CPU1_BOOTR2")
		)
	)
	(footprint ""
		(layer "F.Cu")
		(at 101.833934 -397.46174 180)
		(property "Reference" "R3496"
			(at 0 0 180)
			(layer "F.SilkS")
			(hide yes)
			(effects
				(font
					(size 1.27 1.27)
				)
			)
		)
		(property "Value" ""
			(at 0 0 180)
			(layer "F.Fab")
			(effects
				(font
					(size 1.27 1.27)
				)
			)
		)
		(duplicate_pad_numbers_are_jumpers no)
		(fp_line
			(start 0.7874 0.4064)
			(end -0.7874 0.4064)
			(stroke
				(width 0.1524)
				(type default)
			)
			(layer "F.SilkS")
		)
		(fp_line
			(start 0.7874 -0.4064)
			(end 0.7874 0.4064)
			(stroke
				(width 0.1524)
				(type default)
			)
			(layer "F.SilkS")
		)
		(fp_line
			(start -0.7874 0.4064)
			(end -0.7874 -0.4064)
			(stroke
				(width 0.1524)
				(type default)
			)
			(layer "F.SilkS")
		)
		(fp_line
			(start -0.7874 -0.4064)
			(end 0.7874 -0.4064)
			(stroke
				(width 0.1524)
				(type default)
			)
			(layer "F.SilkS")
		)
		(fp_line
			(start 0.67945 0.3048)
			(end 0.120396 0.3048)
			(stroke
				(width 0.1)
				(type default)
			)
			(layer "F.Fab")
		)
		(fp_line
			(start 0.67945 -0.3048)
			(end 0.67945 0.3048)
			(stroke
				(width 0.1)
				(type default)
			)
			(layer "F.Fab")
		)
		(fp_line
			(start 0.12065 -0.2794)
			(end 0.12065 -0.3048)
			(stroke
				(width 0.1)
				(type default)
			)
			(layer "F.Fab")
		)
		(fp_line
			(start 0.12065 -0.3048)
			(end 0.67945 -0.3048)
			(stroke
				(width 0.1)
				(type default)
			)
			(layer "F.Fab")
		)
		(fp_line
			(start 0.120396 0.3048)
			(end 0.120396 0.2794)
			(stroke
				(width 0.1)
				(type default)
			)
			(layer "F.Fab")
		)
		(fp_line
			(start 0.120396 0.2794)
			(end -0.12065 0.2794)
			(stroke
				(width 0.1)
				(type default)
			)
			(layer "F.Fab")
		)
		(fp_line
			(start -0.12065 0.3048)
			(end -0.67945 0.3048)
			(stroke
				(width 0.1)
				(type default)
			)
			(layer "F.Fab")
		)
		(fp_line
			(start -0.12065 0.2794)
			(end -0.12065 0.3048)
			(stroke
				(width 0.1)
				(type default)
			)
			(layer "F.Fab")
		)
		(fp_line
			(start -0.12065 -0.2794)
			(end 0.12065 -0.2794)
			(stroke
				(width 0.1)
				(type default)
			)
			(layer "F.Fab")
		)
		(fp_line
			(start -0.12065 -0.305054)
			(end -0.12065 -0.2794)
			(stroke
				(width 0.1)
				(type default)
			)
			(layer "F.Fab")
		)
		(fp_line
			(start -0.67945 0.3048)
			(end -0.67945 -0.305054)
			(stroke
				(width 0.1)
				(type default)
			)
			(layer "F.Fab")
		)
		(fp_line
			(start -0.67945 -0.305054)
			(end -0.12065 -0.305054)
			(stroke
				(width 0.1)
				(type default)
			)
			(layer "F.Fab")
		)
		(pad "1" smd circle
			(at -0.40005 0 180)
			(size 0 0)
			(layers "F.Cu" "F.Mask" "F.Paste")
			(net "GPU_FPGA_EROT_RST_BUF_R_N")
		)
		(pad "2" smd circle
			(at 0.40005 0 180)
			(size 0 0)
			(layers "F.Cu" "F.Mask" "F.Paste")
			(net "GPU_FPGA_EROT_RST_BUF_N")
		)
	)
	(footprint ""
		(layer "F.Cu")
		(at 87.947246 -57.279286 90)
		(property "Reference" "PC2140"
			(at 0 0 90)
			(layer "F.SilkS")
			(hide yes)
			(effects
				(font
					(size 1.27 1.27)
				)
			)
		)
		(property "Value" ""
			(at 0 0 90)
			(layer "F.Fab")
			(effects
				(font
					(size 1.27 1.27)
				)
			)
		)
		(duplicate_pad_numbers_are_jumpers no)
		(fp_line
			(start 0.7874 -0.4064)
			(end 0.7874 0.4064)
			(stroke
				(width 0.1524)
				(type default)
			)
			(layer "F.SilkS")
		)
		(fp_line
			(start -0.7874 -0.4064)
			(end 0.7874 -0.4064)
			(stroke
				(width 0.1524)
				(type default)
			)
			(layer "F.SilkS")
		)
		(fp_line
			(start 0.7874 0.4064)
			(end -0.7874 0.4064)
			(stroke
				(width 0.1524)
				(type default)
			)
			(layer "F.SilkS")
		)
		(fp_line
			(start -0.7874 0.4064)
			(end -0.7874 -0.4064)
			(stroke
				(width 0.1524)
				(type default)
			)
			(layer "F.SilkS")
		)
		(fp_line
			(start -0.12065 -0.305054)
			(end -0.12065 -0.2794)
			(stroke
				(width 0.1)
				(type default)
			)
			(layer "F.Fab")
		)
		(fp_line
			(start -0.67945 -0.305054)
			(end -0.12065 -0.305054)
			(stroke
				(width 0.1)
				(type default)
			)
			(layer "F.Fab")
		)
		(fp_line
			(start 0.67945 -0.3048)
			(end 0.67945 0.3048)
			(stroke
				(width 0.1)
				(type default)
			)
			(layer "F.Fab")
		)
		(fp_line
			(start 0.12065 -0.3048)
			(end 0.67945 -0.3048)
			(stroke
				(width 0.1)
				(type default)
			)
			(layer "F.Fab")
		)
		(fp_line
			(start 0.12065 -0.2794)
			(end 0.12065 -0.3048)
			(stroke
				(width 0.1)
				(type default)
			)
			(layer "F.Fab")
		)
		(fp_line
			(start -0.12065 -0.2794)
			(end 0.12065 -0.2794)
			(stroke
				(width 0.1)
				(type default)
			)
			(layer "F.Fab")
		)
		(fp_line
			(start 0.120396 0.2794)
			(end -0.12065 0.2794)
			(stroke
				(width 0.1)
				(type default)
			)
			(layer "F.Fab")
		)
		(fp_line
			(start -0.12065 0.2794)
			(end -0.12065 0.3048)
			(stroke
				(width 0.1)
				(type default)
			)
			(layer "F.Fab")
		)
		(fp_line
			(start 0.67945 0.3048)
			(end 0.120396 0.3048)
			(stroke
				(width 0.1)
				(type default)
			)
			(layer "F.Fab")
		)
		(fp_line
			(start 0.120396 0.3048)
			(end 0.120396 0.2794)
			(stroke
				(width 0.1)
				(type default)
			)
			(layer "F.Fab")
		)
		(fp_line
			(start -0.12065 0.3048)
			(end -0.67945 0.3048)
			(stroke
				(width 0.1)
				(type default)
			)
			(layer "F.Fab")
		)
		(fp_line
			(start -0.67945 0.3048)
			(end -0.67945 -0.305054)
			(stroke
				(width 0.1)
				(type default)
			)
			(layer "F.Fab")
		)
		(pad "1" smd circle
			(at -0.40005 0 90)
			(size 0 0)
			(layers "F.Cu" "F.Mask" "F.Paste")
			(net "P3V3_AUX")
		)
		(pad "2" smd circle
			(at 0.40005 0 90)
			(size 0 0)
			(layers "F.Cu" "F.Mask" "F.Paste")
			(net "GND")
		)
	)
	(footprint ""
		(layer "F.Cu")
		(at 36.884102 -122.380502 90)
		(property "Reference" "R2449"
			(at 0 0 90)
			(layer "F.SilkS")
			(hide yes)
			(effects
				(font
					(size 1.27 1.27)
				)
			)
		)
		(property "Value" ""
			(at 0 0 90)
			(layer "F.Fab")
			(effects
				(font
					(size 1.27 1.27)
				)
			)
		)
		(duplicate_pad_numbers_are_jumpers no)
		(fp_line
			(start 0.7874 -0.4064)
			(end 0.7874 0.4064)
			(stroke
				(width 0.1524)
				(type default)
			)
			(layer "F.SilkS")
		)
		(fp_line
			(start -0.7874 -0.4064)
			(end 0.7874 -0.4064)
			(stroke
				(width 0.1524)
				(type default)
			)
			(layer "F.SilkS")
		)
		(fp_line
			(start 0.7874 0.4064)
			(end -0.7874 0.4064)
			(stroke
				(width 0.1524)
				(type default)
			)
			(layer "F.SilkS")
		)
		(fp_line
			(start -0.7874 0.4064)
			(end -0.7874 -0.4064)
			(stroke
				(width 0.1524)
				(type default)
			)
			(layer "F.SilkS")
		)
		(fp_line
			(start -0.12065 -0.305054)
			(end -0.12065 -0.2794)
			(stroke
				(width 0.1)
				(type default)
			)
			(layer "F.Fab")
		)
		(fp_line
			(start -0.67945 -0.305054)
			(end -0.12065 -0.305054)
			(stroke
				(width 0.1)
				(type default)
			)
			(layer "F.Fab")
		)
		(fp_line
			(start 0.67945 -0.3048)
			(end 0.67945 0.3048)
			(stroke
				(width 0.1)
				(type default)
			)
			(layer "F.Fab")
		)
		(fp_line
			(start 0.12065 -0.3048)
			(end 0.67945 -0.3048)
			(stroke
				(width 0.1)
				(type default)
			)
			(layer "F.Fab")
		)
		(fp_line
			(start 0.12065 -0.2794)
			(end 0.12065 -0.3048)
			(stroke
				(width 0.1)
				(type default)
			)
			(layer "F.Fab")
		)
		(fp_line
			(start -0.12065 -0.2794)
			(end 0.12065 -0.2794)
			(stroke
				(width 0.1)
				(type default)
			)
			(layer "F.Fab")
		)
		(fp_line
			(start 0.120396 0.2794)
			(end -0.12065 0.2794)
			(stroke
				(width 0.1)
				(type default)
			)
			(layer "F.Fab")
		)
		(fp_line
			(start -0.12065 0.2794)
			(end -0.12065 0.3048)
			(stroke
				(width 0.1)
				(type default)
			)
			(layer "F.Fab")
		)
		(fp_line
			(start 0.67945 0.3048)
			(end 0.120396 0.3048)
			(stroke
				(width 0.1)
				(type default)
			)
			(layer "F.Fab")
		)
		(fp_line
			(start 0.120396 0.3048)
			(end 0.120396 0.2794)
			(stroke
				(width 0.1)
				(type default)
			)
			(layer "F.Fab")
		)
		(fp_line
			(start -0.12065 0.3048)
			(end -0.67945 0.3048)
			(stroke
				(width 0.1)
				(type default)
			)
			(layer "F.Fab")
		)
		(fp_line
			(start -0.67945 0.3048)
			(end -0.67945 -0.305054)
			(stroke
				(width 0.1)
				(type default)
			)
			(layer "F.Fab")
		)
		(pad "1" smd circle
			(at -0.40005 0 90)
			(size 0 0)
			(layers "F.Cu" "F.Mask" "F.Paste")
			(net "SMB_VR_3V3AUX_SCL")
		)
		(pad "2" smd circle
			(at 0.40005 0 90)
			(size 0 0)
			(layers "F.Cu" "F.Mask" "F.Paste")
			(net "SMB_VR_3V3AUX_SCL_R1")
		)
	)
	(footprint ""
		(layer "F.Cu")
		(at 138.55954 -347.520514 90)
		(property "Reference" "PR1792"
			(at 0 0 90)
			(layer "F.SilkS")
			(hide yes)
			(effects
				(font
					(size 1.27 1.27)
				)
			)
		)
		(property "Value" ""
			(at 0 0 90)
			(layer "F.Fab")
			(effects
				(font
					(size 1.27 1.27)
				)
			)
		)
		(duplicate_pad_numbers_are_jumpers no)
		(fp_line
			(start 0.7874 -0.4064)
			(end 0.7874 0.4064)
			(stroke
				(width 0.1524)
				(type default)
			)
			(layer "F.SilkS")
		)
		(fp_line
			(start -0.7874 -0.4064)
			(end 0.7874 -0.4064)
			(stroke
				(width 0.1524)
				(type default)
			)
			(layer "F.SilkS")
		)
		(fp_line
			(start 0.7874 0.4064)
			(end -0.7874 0.4064)
			(stroke
				(width 0.1524)
				(type default)
			)
			(layer "F.SilkS")
		)
		(fp_line
			(start -0.7874 0.4064)
			(end -0.7874 -0.4064)
			(stroke
				(width 0.1524)
				(type default)
			)
			(layer "F.SilkS")
		)
		(fp_line
			(start -0.12065 -0.305054)
			(end -0.12065 -0.2794)
			(stroke
				(width 0.1)
				(type default)
			)
			(layer "F.Fab")
		)
		(fp_line
			(start -0.67945 -0.305054)
			(end -0.12065 -0.305054)
			(stroke
				(width 0.1)
				(type default)
			)
			(layer "F.Fab")
		)
		(fp_line
			(start 0.67945 -0.3048)
			(end 0.67945 0.3048)
			(stroke
				(width 0.1)
				(type default)
			)
			(layer "F.Fab")
		)
		(fp_line
			(start 0.12065 -0.3048)
			(end 0.67945 -0.3048)
			(stroke
				(width 0.1)
				(type default)
			)
			(layer "F.Fab")
		)
		(fp_line
			(start 0.12065 -0.2794)
			(end 0.12065 -0.3048)
			(stroke
				(width 0.1)
				(type default)
			)
			(layer "F.Fab")
		)
		(fp_line
			(start -0.12065 -0.2794)
			(end 0.12065 -0.2794)
			(stroke
				(width 0.1)
				(type default)
			)
			(layer "F.Fab")
		)
		(fp_line
			(start 0.120396 0.2794)
			(end -0.12065 0.2794)
			(stroke
				(width 0.1)
				(type default)
			)
			(layer "F.Fab")
		)
		(fp_line
			(start -0.12065 0.2794)
			(end -0.12065 0.3048)
			(stroke
				(width 0.1)
				(type default)
			)
			(layer "F.Fab")
		)
		(fp_line
			(start 0.67945 0.3048)
			(end 0.120396 0.3048)
			(stroke
				(width 0.1)
				(type default)
			)
			(layer "F.Fab")
		)
		(fp_line
			(start 0.120396 0.3048)
			(end 0.120396 0.2794)
			(stroke
				(width 0.1)
				(type default)
			)
			(layer "F.Fab")
		)
		(fp_line
			(start -0.12065 0.3048)
			(end -0.67945 0.3048)
			(stroke
				(width 0.1)
				(type default)
			)
			(layer "F.Fab")
		)
		(fp_line
			(start -0.67945 0.3048)
			(end -0.67945 -0.305054)
			(stroke
				(width 0.1)
				(type default)
			)
			(layer "F.Fab")
		)
		(pad "1" smd circle
			(at -0.40005 0 90)
			(size 0 0)
			(layers "F.Cu" "F.Mask" "F.Paste")
			(net "SW_PVCCIN_CPU1_BOOT8")
		)
		(pad "2" smd circle
			(at 0.40005 0 90)
			(size 0 0)
			(layers "F.Cu" "F.Mask" "F.Paste")
			(net "SW_PVCCIN_CPU1_BOOT8_R")
		)
	)
	(footprint ""
		(layer "F.Cu")
		(at 352.089974 -354.495862 -90)
		(property "Reference" "C3268"
			(at 0 0 270)
			(layer "F.SilkS")
			(hide yes)
			(effects
				(font
					(size 1.27 1.27)
				)
			)
		)
		(property "Value" ""
			(at 0 0 270)
			(layer "F.Fab")
			(effects
				(font
					(size 1.27 1.27)
				)
			)
		)
		(duplicate_pad_numbers_are_jumpers no)
		(fp_line
			(start -0.7874 0.4064)
			(end -0.7874 -0.4064)
			(stroke
				(width 0.1524)
				(type default)
			)
			(layer "F.SilkS")
		)
		(fp_line
			(start 0.7874 0.4064)
			(end -0.7874 0.4064)
			(stroke
				(width 0.1524)
				(type default)
			)
			(layer "F.SilkS")
		)
		(fp_line
			(start -0.7874 -0.4064)
			(end 0.7874 -0.4064)
			(stroke
				(width 0.1524)
				(type default)
			)
			(layer "F.SilkS")
		)
		(fp_line
			(start 0.7874 -0.4064)
			(end 0.7874 0.4064)
			(stroke
				(width 0.1524)
				(type default)
			)
			(layer "F.SilkS")
		)
		(fp_line
			(start -0.67945 0.3048)
			(end -0.67945 -0.305054)
			(stroke
				(width 0.1)
				(type default)
			)
			(layer "F.Fab")
		)
		(fp_line
			(start -0.12065 0.3048)
			(end -0.67945 0.3048)
			(stroke
				(width 0.1)
				(type default)
			)
			(layer "F.Fab")
		)
		(fp_line
			(start 0.120396 0.3048)
			(end 0.120396 0.2794)
			(stroke
				(width 0.1)
				(type default)
			)
			(layer "F.Fab")
		)
		(fp_line
			(start 0.67945 0.3048)
			(end 0.120396 0.3048)
			(stroke
				(width 0.1)
				(type default)
			)
			(layer "F.Fab")
		)
		(fp_line
			(start -0.12065 0.2794)
			(end -0.12065 0.3048)
			(stroke
				(width 0.1)
				(type default)
			)
			(layer "F.Fab")
		)
		(fp_line
			(start 0.120396 0.2794)
			(end -0.12065 0.2794)
			(stroke
				(width 0.1)
				(type default)
			)
			(layer "F.Fab")
		)
		(fp_line
			(start -0.12065 -0.2794)
			(end 0.12065 -0.2794)
			(stroke
				(width 0.1)
				(type default)
			)
			(layer "F.Fab")
		)
		(fp_line
			(start 0.12065 -0.2794)
			(end 0.12065 -0.3048)
			(stroke
				(width 0.1)
				(type default)
			)
			(layer "F.Fab")
		)
		(fp_line
			(start 0.12065 -0.3048)
			(end 0.67945 -0.3048)
			(stroke
				(width 0.1)
				(type default)
			)
			(layer "F.Fab")
		)
		(fp_line
			(start 0.67945 -0.3048)
			(end 0.67945 0.3048)
			(stroke
				(width 0.1)
				(type default)
			)
			(layer "F.Fab")
		)
		(fp_line
			(start -0.67945 -0.305054)
			(end -0.12065 -0.305054)
			(stroke
				(width 0.1)
				(type default)
			)
			(layer "F.Fab")
		)
		(fp_line
			(start -0.12065 -0.305054)
			(end -0.12065 -0.2794)
			(stroke
				(width 0.1)
				(type default)
			)
			(layer "F.Fab")
		)
		(pad "1" smd circle
			(at -0.40005 0 270)
			(size 0 0)
			(layers "F.Cu" "F.Mask" "F.Paste")
			(net "PVCCFA_EHV_FIVRA_CPU0_EN_R")
		)
		(pad "2" smd circle
			(at 0.40005 0 270)
			(size 0 0)
			(layers "F.Cu" "F.Mask" "F.Paste")
			(net "GND")
		)
	)
)
